(kicad_pcb
	(version 20260206)
	(generator "pcbnew")
	(generator_version "10.0")
	(general
		(thickness 1.6)
		(legacy_teardrops no)
	)
	(paper "A4")
	(title_block
		(title "04192023_DAF0TMB3IC0_F0TG_MB_C_brd_V02_OCP.brd")
		(comment 1 "Grand Teton / footprints 5943-5950 of 8354")
	)
	(layers
		(0 "F.Cu" signal "TOP")
		(4 "In1.Cu" signal "GND")
		(6 "In2.Cu" signal "IN1")
		(8 "In3.Cu" signal "GND1")
		(10 "In4.Cu" signal "IN2")
		(12 "In5.Cu" signal "GND2")
		(14 "In6.Cu" signal "IN3")
		(16 "In7.Cu" signal "GND3")
		(18 "In8.Cu" signal "VCC")
		(20 "In9.Cu" signal "VCC1")
		(22 "In10.Cu" signal "GND4")
		(24 "In11.Cu" signal "IN4")
		(26 "In12.Cu" signal "GND5")
		(28 "In13.Cu" signal "IN5")
		(30 "In14.Cu" signal "GND6")
		(32 "In15.Cu" signal "IN6")
		(34 "In16.Cu" signal "GND7")
		(2 "B.Cu" signal "BOTTOM")
		(9 "F.Adhes" user "F.Adhesive")
		(11 "B.Adhes" user "B.Adhesive")
		(13 "F.Paste" user "Package Geometry/Pastemask Top")
		(15 "B.Paste" user "Package Geometry/Pastemask Bottom")
		(5 "F.SilkS" user "Ref Des/Silkscreen Top")
		(7 "B.SilkS" user "Ref Des/Silkscreen Bottom")
		(1 "F.Mask" user "Board Geometry/Soldermask Top")
		(3 "B.Mask" user "Board Geometry/Soldermask Bottom")
		(17 "Dwgs.User" user "User.Drawings")
		(19 "Cmts.User" user "User.Comments")
		(21 "Eco1.User" user "User.Eco1")
		(23 "Eco2.User" user "User.Eco2")
		(25 "Edge.Cuts" user "Board Geometry/Outline")
		(27 "Margin" user)
		(31 "F.CrtYd" user "Package Geometry/Place Bound Top")
		(29 "B.CrtYd" user "Package Geometry/Place Bound Bottom")
		(35 "F.Fab" user "Ref Des/Assembly Top")
		(33 "B.Fab" user "Ref Des/Assembly Bottom")
	)
	(footprint ""
		(layer "B.Cu")
		(at 105.224834 -245.487952)
		(property "Reference" "C2309"
			(at 0 0 0)
			(layer "B.SilkS")
			(hide yes)
			(effects
				(font
					(size 1.27 1.27)
				)
				(justify mirror)
			)
		)
		(property "Value" ""
			(at 0 0 0)
			(layer "B.Fab")
			(effects
				(font
					(size 1.27 1.27)
				)
				(justify mirror)
			)
		)
		(duplicate_pad_numbers_are_jumpers no)
		(fp_line
			(start -0.7874 -0.4064)
			(end -0.7874 0.4064)
			(stroke
				(width 0.1524)
				(type default)
			)
			(layer "B.SilkS")
		)
		(fp_line
			(start -0.7874 0.4064)
			(end 0.7874 0.4064)
			(stroke
				(width 0.1524)
				(type default)
			)
			(layer "B.SilkS")
		)
		(fp_line
			(start 0.7874 -0.4064)
			(end -0.7874 -0.4064)
			(stroke
				(width 0.1524)
				(type default)
			)
			(layer "B.SilkS")
		)
		(fp_line
			(start 0.7874 0.4064)
			(end 0.7874 -0.4064)
			(stroke
				(width 0.1524)
				(type default)
			)
			(layer "B.SilkS")
		)
		(fp_line
			(start -0.67945 -0.3048)
			(end -0.67945 0.3048)
			(stroke
				(width 0.1)
				(type default)
			)
			(layer "B.Fab")
		)
		(fp_line
			(start -0.67945 0.3048)
			(end -0.120396 0.3048)
			(stroke
				(width 0.1)
				(type default)
			)
			(layer "B.Fab")
		)
		(fp_line
			(start -0.12065 -0.3048)
			(end -0.67945 -0.3048)
			(stroke
				(width 0.1)
				(type default)
			)
			(layer "B.Fab")
		)
		(fp_line
			(start -0.12065 -0.2794)
			(end -0.12065 -0.3048)
			(stroke
				(width 0.1)
				(type default)
			)
			(layer "B.Fab")
		)
		(fp_line
			(start -0.120396 0.2794)
			(end 0.12065 0.2794)
			(stroke
				(width 0.1)
				(type default)
			)
			(layer "B.Fab")
		)
		(fp_line
			(start -0.120396 0.3048)
			(end -0.120396 0.2794)
			(stroke
				(width 0.1)
				(type default)
			)
			(layer "B.Fab")
		)
		(fp_line
			(start 0.12065 -0.305054)
			(end 0.12065 -0.2794)
			(stroke
				(width 0.1)
				(type default)
			)
			(layer "B.Fab")
		)
		(fp_line
			(start 0.12065 -0.2794)
			(end -0.12065 -0.2794)
			(stroke
				(width 0.1)
				(type default)
			)
			(layer "B.Fab")
		)
		(fp_line
			(start 0.12065 0.2794)
			(end 0.12065 0.3048)
			(stroke
				(width 0.1)
				(type default)
			)
			(layer "B.Fab")
		)
		(fp_line
			(start 0.12065 0.3048)
			(end 0.67945 0.3048)
			(stroke
				(width 0.1)
				(type default)
			)
			(layer "B.Fab")
		)
		(fp_line
			(start 0.67945 -0.305054)
			(end 0.12065 -0.305054)
			(stroke
				(width 0.1)
				(type default)
			)
			(layer "B.Fab")
		)
		(fp_line
			(start 0.67945 0.3048)
			(end 0.67945 -0.305054)
			(stroke
				(width 0.1)
				(type default)
			)
			(layer "B.Fab")
		)
		(pad "1" smd circle
			(at 0.40005 0 180)
			(size 0 0)
			(layers "B.Cu" "B.Mask" "B.Paste")
			(net "PVDDCR_CPU0_P1")
		)
		(pad "2" smd circle
			(at -0.40005 0 180)
			(size 0 0)
			(layers "B.Cu" "B.Mask" "B.Paste")
			(net "GND")
		)
	)
	(footprint ""
		(layer "B.Cu")
		(at 404.206202 -395.148562 90)
		(property "Reference" "C797"
			(at 0 0 90)
			(layer "B.SilkS")
			(hide yes)
			(effects
				(font
					(size 1.27 1.27)
				)
				(justify mirror)
			)
		)
		(property "Value" ""
			(at 0 0 90)
			(layer "B.Fab")
			(effects
				(font
					(size 1.27 1.27)
				)
				(justify mirror)
			)
		)
		(duplicate_pad_numbers_are_jumpers no)
		(fp_line
			(start 0.299974 -0.150114)
			(end -0.299974 -0.150114)
			(stroke
				(width 0.1)
				(type default)
			)
			(layer "B.Fab")
		)
		(fp_line
			(start -0.299974 -0.150114)
			(end -0.299974 0.150114)
			(stroke
				(width 0.1)
				(type default)
			)
			(layer "B.Fab")
		)
		(fp_line
			(start 0.299974 0.150114)
			(end 0.299974 -0.150114)
			(stroke
				(width 0.1)
				(type default)
			)
			(layer "B.Fab")
		)
		(fp_line
			(start -0.299974 0.150114)
			(end 0.299974 0.150114)
			(stroke
				(width 0.1)
				(type default)
			)
			(layer "B.Fab")
		)
		(pad "1" smd rect
			(at 0.2667 0 270)
			(size 0.3048 0.381)
			(layers "B.Cu" "B.Mask" "B.Paste")
			(net "P0V9_CPU0_RT2_2A")
		)
		(pad "2" smd rect
			(at -0.2667 0 270)
			(size 0.3048 0.381)
			(layers "B.Cu" "B.Mask" "B.Paste")
			(net "GND")
		)
	)
	(footprint ""
		(layer "B.Cu")
		(at 369.62588 -257.930142)
		(property "Reference" "C2544"
			(at 0 0 0)
			(layer "B.SilkS")
			(hide yes)
			(effects
				(font
					(size 1.27 1.27)
				)
				(justify mirror)
			)
		)
		(property "Value" ""
			(at 0 0 0)
			(layer "B.Fab")
			(effects
				(font
					(size 1.27 1.27)
				)
				(justify mirror)
			)
		)
		(duplicate_pad_numbers_are_jumpers no)
		(fp_line
			(start -0.7874 -0.4064)
			(end -0.7874 0.4064)
			(stroke
				(width 0.1524)
				(type default)
			)
			(layer "B.SilkS")
		)
		(fp_line
			(start -0.7874 0.4064)
			(end 0.7874 0.4064)
			(stroke
				(width 0.1524)
				(type default)
			)
			(layer "B.SilkS")
		)
		(fp_line
			(start 0.7874 -0.4064)
			(end -0.7874 -0.4064)
			(stroke
				(width 0.1524)
				(type default)
			)
			(layer "B.SilkS")
		)
		(fp_line
			(start 0.7874 0.4064)
			(end 0.7874 -0.4064)
			(stroke
				(width 0.1524)
				(type default)
			)
			(layer "B.SilkS")
		)
		(fp_line
			(start -0.67945 -0.3048)
			(end -0.67945 0.3048)
			(stroke
				(width 0.1)
				(type default)
			)
			(layer "B.Fab")
		)
		(fp_line
			(start -0.67945 0.3048)
			(end -0.120396 0.3048)
			(stroke
				(width 0.1)
				(type default)
			)
			(layer "B.Fab")
		)
		(fp_line
			(start -0.12065 -0.3048)
			(end -0.67945 -0.3048)
			(stroke
				(width 0.1)
				(type default)
			)
			(layer "B.Fab")
		)
		(fp_line
			(start -0.12065 -0.2794)
			(end -0.12065 -0.3048)
			(stroke
				(width 0.1)
				(type default)
			)
			(layer "B.Fab")
		)
		(fp_line
			(start -0.120396 0.2794)
			(end 0.12065 0.2794)
			(stroke
				(width 0.1)
				(type default)
			)
			(layer "B.Fab")
		)
		(fp_line
			(start -0.120396 0.3048)
			(end -0.120396 0.2794)
			(stroke
				(width 0.1)
				(type default)
			)
			(layer "B.Fab")
		)
		(fp_line
			(start 0.12065 -0.305054)
			(end 0.12065 -0.2794)
			(stroke
				(width 0.1)
				(type default)
			)
			(layer "B.Fab")
		)
		(fp_line
			(start 0.12065 -0.2794)
			(end -0.12065 -0.2794)
			(stroke
				(width 0.1)
				(type default)
			)
			(layer "B.Fab")
		)
		(fp_line
			(start 0.12065 0.2794)
			(end 0.12065 0.3048)
			(stroke
				(width 0.1)
				(type default)
			)
			(layer "B.Fab")
		)
		(fp_line
			(start 0.12065 0.3048)
			(end 0.67945 0.3048)
			(stroke
				(width 0.1)
				(type default)
			)
			(layer "B.Fab")
		)
		(fp_line
			(start 0.67945 -0.305054)
			(end 0.12065 -0.305054)
			(stroke
				(width 0.1)
				(type default)
			)
			(layer "B.Fab")
		)
		(fp_line
			(start 0.67945 0.3048)
			(end 0.67945 -0.305054)
			(stroke
				(width 0.1)
				(type default)
			)
			(layer "B.Fab")
		)
		(pad "1" smd circle
			(at 0.40005 0 180)
			(size 0 0)
			(layers "B.Cu" "B.Mask" "B.Paste")
			(net "PVDDCR_SOC_P0")
		)
		(pad "2" smd circle
			(at -0.40005 0 180)
			(size 0 0)
			(layers "B.Cu" "B.Mask" "B.Paste")
			(net "GND")
		)
	)
	(footprint ""
		(layer "B.Cu")
		(at 254.635 -339.63864 180)
		(property "Reference" "R1371"
			(at 0 0 0)
			(layer "B.SilkS")
			(hide yes)
			(effects
				(font
					(size 1.27 1.27)
				)
				(justify mirror)
			)
		)
		(property "Value" ""
			(at 0 0 0)
			(layer "B.Fab")
			(effects
				(font
					(size 1.27 1.27)
				)
				(justify mirror)
			)
		)
		(duplicate_pad_numbers_are_jumpers no)
		(fp_line
			(start 0.32512 0.175006)
			(end 0.32512 -0.175006)
			(stroke
				(width 0.1)
				(type default)
			)
			(layer "B.Fab")
		)
		(fp_line
			(start 0.32512 -0.175006)
			(end -0.32512 -0.175006)
			(stroke
				(width 0.1)
				(type default)
			)
			(layer "B.Fab")
		)
		(fp_line
			(start -0.32512 0.175006)
			(end 0.32512 0.175006)
			(stroke
				(width 0.1)
				(type default)
			)
			(layer "B.Fab")
		)
		(fp_line
			(start -0.32512 -0.175006)
			(end -0.32512 0.175006)
			(stroke
				(width 0.1)
				(type default)
			)
			(layer "B.Fab")
		)
		(pad "1" smd rect
			(at 0.2667 0)
			(size 0.3048 0.381)
			(layers "B.Cu" "B.Mask" "B.Paste")
			(net "P1V8_CPU0_RT_1D")
		)
		(pad "2" smd rect
			(at -0.2667 0 180)
			(size 0.3048 0.381)
			(layers "B.Cu" "B.Mask" "B.Paste")
			(net "SMB_RT_CPU0_P1_ROM_MUX_2D_R_SDA")
		)
	)
	(footprint ""
		(layer "B.Cu")
		(at 418.998908 -428.682912 180)
		(property "Reference" "R1209"
			(at 0 0 0)
			(layer "B.SilkS")
			(hide yes)
			(effects
				(font
					(size 1.27 1.27)
				)
				(justify mirror)
			)
		)
		(property "Value" ""
			(at 0 0 0)
			(layer "B.Fab")
			(effects
				(font
					(size 1.27 1.27)
				)
				(justify mirror)
			)
		)
		(duplicate_pad_numbers_are_jumpers no)
		(fp_line
			(start 0.32512 0.175006)
			(end 0.32512 -0.175006)
			(stroke
				(width 0.1)
				(type default)
			)
			(layer "B.Fab")
		)
		(fp_line
			(start 0.32512 -0.175006)
			(end -0.32512 -0.175006)
			(stroke
				(width 0.1)
				(type default)
			)
			(layer "B.Fab")
		)
		(fp_line
			(start -0.32512 0.175006)
			(end 0.32512 0.175006)
			(stroke
				(width 0.1)
				(type default)
			)
			(layer "B.Fab")
		)
		(fp_line
			(start -0.32512 -0.175006)
			(end -0.32512 0.175006)
			(stroke
				(width 0.1)
				(type default)
			)
			(layer "B.Fab")
		)
		(pad "1" smd rect
			(at 0.2667 0)
			(size 0.3048 0.381)
			(layers "B.Cu" "B.Mask" "B.Paste")
			(net "RST_SMB_RT_ROM_R1_N")
		)
		(pad "2" smd rect
			(at -0.2667 0 180)
			(size 0.3048 0.381)
			(layers "B.Cu" "B.Mask" "B.Paste")
			(net "FM_SMB_RT_ROM_MUX8_SEL")
		)
	)
	(footprint ""
		(layer "B.Cu")
		(at 231.829102 -329.365102 180)
		(property "Reference" "R1249"
			(at 0 0 0)
			(layer "B.SilkS")
			(hide yes)
			(effects
				(font
					(size 1.27 1.27)
				)
				(justify mirror)
			)
		)
		(property "Value" ""
			(at 0 0 0)
			(layer "B.Fab")
			(effects
				(font
					(size 1.27 1.27)
				)
				(justify mirror)
			)
		)
		(duplicate_pad_numbers_are_jumpers no)
		(fp_line
			(start 0.7874 0.4064)
			(end 0.7874 -0.4064)
			(stroke
				(width 0.1524)
				(type default)
			)
			(layer "B.SilkS")
		)
		(fp_line
			(start 0.7874 -0.4064)
			(end -0.7874 -0.4064)
			(stroke
				(width 0.1524)
				(type default)
			)
			(layer "B.SilkS")
		)
		(fp_line
			(start -0.7874 0.4064)
			(end 0.7874 0.4064)
			(stroke
				(width 0.1524)
				(type default)
			)
			(layer "B.SilkS")
		)
		(fp_line
			(start -0.7874 -0.4064)
			(end -0.7874 0.4064)
			(stroke
				(width 0.1524)
				(type default)
			)
			(layer "B.SilkS")
		)
		(fp_line
			(start 0.67945 0.3048)
			(end 0.67945 -0.305054)
			(stroke
				(width 0.1)
				(type default)
			)
			(layer "B.Fab")
		)
		(fp_line
			(start 0.67945 -0.305054)
			(end 0.12065 -0.305054)
			(stroke
				(width 0.1)
				(type default)
			)
			(layer "B.Fab")
		)
		(fp_line
			(start 0.12065 0.3048)
			(end 0.67945 0.3048)
			(stroke
				(width 0.1)
				(type default)
			)
			(layer "B.Fab")
		)
		(fp_line
			(start 0.12065 0.2794)
			(end 0.12065 0.3048)
			(stroke
				(width 0.1)
				(type default)
			)
			(layer "B.Fab")
		)
		(fp_line
			(start 0.12065 -0.2794)
			(end -0.12065 -0.2794)
			(stroke
				(width 0.1)
				(type default)
			)
			(layer "B.Fab")
		)
		(fp_line
			(start 0.12065 -0.305054)
			(end 0.12065 -0.2794)
			(stroke
				(width 0.1)
				(type default)
			)
			(layer "B.Fab")
		)
		(fp_line
			(start -0.120396 0.3048)
			(end -0.120396 0.2794)
			(stroke
				(width 0.1)
				(type default)
			)
			(layer "B.Fab")
		)
		(fp_line
			(start -0.120396 0.2794)
			(end 0.12065 0.2794)
			(stroke
				(width 0.1)
				(type default)
			)
			(layer "B.Fab")
		)
		(fp_line
			(start -0.12065 -0.2794)
			(end -0.12065 -0.3048)
			(stroke
				(width 0.1)
				(type default)
			)
			(layer "B.Fab")
		)
		(fp_line
			(start -0.12065 -0.3048)
			(end -0.67945 -0.3048)
			(stroke
				(width 0.1)
				(type default)
			)
			(layer "B.Fab")
		)
		(fp_line
			(start -0.67945 0.3048)
			(end -0.120396 0.3048)
			(stroke
				(width 0.1)
				(type default)
			)
			(layer "B.Fab")
		)
		(fp_line
			(start -0.67945 -0.3048)
			(end -0.67945 0.3048)
			(stroke
				(width 0.1)
				(type default)
			)
			(layer "B.Fab")
		)
		(pad "1" smd rect
			(at 0.40005 0 180)
			(size 0.4572 0.508)
			(layers "B.Cu" "B.Mask" "B.Paste")
			(net "PVDD18_S5_P1_ADC")
		)
		(pad "2" smd rect
			(at -0.40005 0 180)
			(size 0.4572 0.508)
			(layers "B.Cu" "B.Mask" "B.Paste")
			(net "PVDD18_S5_P1_ADC_MAM")
		)
	)
	(footprint ""
		(layer "B.Cu")
		(at 423.256456 -194.88531 180)
		(property "Reference" "R1575"
			(at 0 0 0)
			(layer "B.SilkS")
			(hide yes)
			(effects
				(font
					(size 1.27 1.27)
				)
				(justify mirror)
			)
		)
		(property "Value" ""
			(at 0 0 0)
			(layer "B.Fab")
			(effects
				(font
					(size 1.27 1.27)
				)
				(justify mirror)
			)
		)
		(duplicate_pad_numbers_are_jumpers no)
		(fp_line
			(start 0.7874 0.4064)
			(end 0.7874 -0.4064)
			(stroke
				(width 0.1524)
				(type default)
			)
			(layer "B.SilkS")
		)
		(fp_line
			(start 0.7874 -0.4064)
			(end -0.7874 -0.4064)
			(stroke
				(width 0.1524)
				(type default)
			)
			(layer "B.SilkS")
		)
		(fp_line
			(start -0.7874 0.4064)
			(end 0.7874 0.4064)
			(stroke
				(width 0.1524)
				(type default)
			)
			(layer "B.SilkS")
		)
		(fp_line
			(start -0.7874 -0.4064)
			(end -0.7874 0.4064)
			(stroke
				(width 0.1524)
				(type default)
			)
			(layer "B.SilkS")
		)
		(fp_line
			(start 0.67945 0.3048)
			(end 0.67945 -0.305054)
			(stroke
				(width 0.1)
				(type default)
			)
			(layer "B.Fab")
		)
		(fp_line
			(start 0.67945 -0.305054)
			(end 0.12065 -0.305054)
			(stroke
				(width 0.1)
				(type default)
			)
			(layer "B.Fab")
		)
		(fp_line
			(start 0.12065 0.3048)
			(end 0.67945 0.3048)
			(stroke
				(width 0.1)
				(type default)
			)
			(layer "B.Fab")
		)
		(fp_line
			(start 0.12065 0.2794)
			(end 0.12065 0.3048)
			(stroke
				(width 0.1)
				(type default)
			)
			(layer "B.Fab")
		)
		(fp_line
			(start 0.12065 -0.2794)
			(end -0.12065 -0.2794)
			(stroke
				(width 0.1)
				(type default)
			)
			(layer "B.Fab")
		)
		(fp_line
			(start 0.12065 -0.305054)
			(end 0.12065 -0.2794)
			(stroke
				(width 0.1)
				(type default)
			)
			(layer "B.Fab")
		)
		(fp_line
			(start -0.120396 0.3048)
			(end -0.120396 0.2794)
			(stroke
				(width 0.1)
				(type default)
			)
			(layer "B.Fab")
		)
		(fp_line
			(start -0.120396 0.2794)
			(end 0.12065 0.2794)
			(stroke
				(width 0.1)
				(type default)
			)
			(layer "B.Fab")
		)
		(fp_line
			(start -0.12065 -0.2794)
			(end -0.12065 -0.3048)
			(stroke
				(width 0.1)
				(type default)
			)
			(layer "B.Fab")
		)
		(fp_line
			(start -0.12065 -0.3048)
			(end -0.67945 -0.3048)
			(stroke
				(width 0.1)
				(type default)
			)
			(layer "B.Fab")
		)
		(fp_line
			(start -0.67945 0.3048)
			(end -0.120396 0.3048)
			(stroke
				(width 0.1)
				(type default)
			)
			(layer "B.Fab")
		)
		(fp_line
			(start -0.67945 -0.3048)
			(end -0.67945 0.3048)
			(stroke
				(width 0.1)
				(type default)
			)
			(layer "B.Fab")
		)
		(pad "1" smd circle
			(at 0.40005 0)
			(size 0 0)
			(layers "B.Cu" "B.Mask" "B.Paste")
			(net "I3C_SPD_DDRGL_CPU0_SCL")
		)
		(pad "2" smd circle
			(at -0.40005 0)
			(size 0 0)
			(layers "B.Cu" "B.Mask" "B.Paste")
			(net "I3C_SPD_DDRH_CPU0_SCL")
		)
	)
	(footprint ""
		(layer "B.Cu")
		(at 197.523608 -105.497376)
		(property "Reference" "R229"
			(at 0 0 0)
			(layer "B.SilkS")
			(hide yes)
			(effects
				(font
					(size 1.27 1.27)
				)
				(justify mirror)
			)
		)
		(property "Value" ""
			(at 0 0 0)
			(layer "B.Fab")
			(effects
				(font
					(size 1.27 1.27)
				)
				(justify mirror)
			)
		)
		(duplicate_pad_numbers_are_jumpers no)
		(fp_line
			(start -0.7874 -0.4064)
			(end -0.7874 0.4064)
			(stroke
				(width 0.1524)
				(type default)
			)
			(layer "B.SilkS")
		)
		(fp_line
			(start -0.7874 0.4064)
			(end 0.7874 0.4064)
			(stroke
				(width 0.1524)
				(type default)
			)
			(layer "B.SilkS")
		)
		(fp_line
			(start 0.7874 -0.4064)
			(end -0.7874 -0.4064)
			(stroke
				(width 0.1524)
				(type default)
			)
			(layer "B.SilkS")
		)
		(fp_line
			(start 0.7874 0.4064)
			(end 0.7874 -0.4064)
			(stroke
				(width 0.1524)
				(type default)
			)
			(layer "B.SilkS")
		)
		(fp_line
			(start -0.67945 -0.3048)
			(end -0.67945 0.3048)
			(stroke
				(width 0.1)
				(type default)
			)
			(layer "B.Fab")
		)
		(fp_line
			(start -0.67945 0.3048)
			(end -0.120396 0.3048)
			(stroke
				(width 0.1)
				(type default)
			)
			(layer "B.Fab")
		)
		(fp_line
			(start -0.12065 -0.3048)
			(end -0.67945 -0.3048)
			(stroke
				(width 0.1)
				(type default)
			)
			(layer "B.Fab")
		)
		(fp_line
			(start -0.12065 -0.2794)
			(end -0.12065 -0.3048)
			(stroke
				(width 0.1)
				(type default)
			)
			(layer "B.Fab")
		)
		(fp_line
			(start -0.120396 0.2794)
			(end 0.12065 0.2794)
			(stroke
				(width 0.1)
				(type default)
			)
			(layer "B.Fab")
		)
		(fp_line
			(start -0.120396 0.3048)
			(end -0.120396 0.2794)
			(stroke
				(width 0.1)
				(type default)
			)
			(layer "B.Fab")
		)
		(fp_line
			(start 0.12065 -0.305054)
			(end 0.12065 -0.2794)
			(stroke
				(width 0.1)
				(type default)
			)
			(layer "B.Fab")
		)
		(fp_line
			(start 0.12065 -0.2794)
			(end -0.12065 -0.2794)
			(stroke
				(width 0.1)
				(type default)
			)
			(layer "B.Fab")
		)
		(fp_line
			(start 0.12065 0.2794)
			(end 0.12065 0.3048)
			(stroke
				(width 0.1)
				(type default)
			)
			(layer "B.Fab")
		)
		(fp_line
			(start 0.12065 0.3048)
			(end 0.67945 0.3048)
			(stroke
				(width 0.1)
				(type default)
			)
			(layer "B.Fab")
		)
		(fp_line
			(start 0.67945 -0.305054)
			(end 0.12065 -0.305054)
			(stroke
				(width 0.1)
				(type default)
			)
			(layer "B.Fab")
		)
		(fp_line
			(start 0.67945 0.3048)
			(end 0.67945 -0.305054)
			(stroke
				(width 0.1)
				(type default)
			)
			(layer "B.Fab")
		)
		(pad "1" smd circle
			(at 0.40005 0 180)
			(size 0 0)
			(layers "B.Cu" "B.Mask" "B.Paste")
			(net "PVDDIO_P0_EN")
		)
		(pad "2" smd circle
			(at -0.40005 0 180)
			(size 0 0)
			(layers "B.Cu" "B.Mask" "B.Paste")
			(net "FM_PVDDIO_P0_EN")
		)
	)
)
